# T6G (Grand Teton) — schematic netlist excerpt (pin names and nets, part order shuffled) for the footprints in the layout excerpt that follows; sources: Cadence DE-HDL packaged netlist, KiCad conversion of 04192023_DAF0TMB3IC0_F0TG_MB_C_brd_V02_OCP.brd

R857  Q_RES  0 5% EMPTY  pkg 0402LF  page 345 : A = P1V8_CPU1_RT_1D ; B = P1V8_CPU1_RT2_1A_1D
R603  Q_RES  0 5% CHIP  pkg 0402LF  page 77 : A = SPI_CPU0_LVC3_CS0_N ; B = SPI_CPU0_LVC3_SCM_CS0_N

(kicad_pcb
	(version 20260206)
	(generator "pcbnew")
	(generator_version "10.0")
	(general
		(thickness 1.6)
		(legacy_teardrops no)
	)
	(paper "A4")
	(title_block
		(title "04192023_DAF0TMB3IC0_F0TG_MB_C_brd_V02_OCP.brd")
		(comment 1 "Grand Teton / footprints 1746-1747 of 8354")
	)
	(layers
		(0 "F.Cu" signal "TOP")
		(4 "In1.Cu" signal "GND")
		(6 "In2.Cu" signal "IN1")
		(8 "In3.Cu" signal "GND1")
		(10 "In4.Cu" signal "IN2")
		(12 "In5.Cu" signal "GND2")
		(14 "In6.Cu" signal "IN3")
		(16 "In7.Cu" signal "GND3")
		(18 "In8.Cu" signal "VCC")
		(20 "In9.Cu" signal "VCC1")
		(22 "In10.Cu" signal "GND4")
		(24 "In11.Cu" signal "IN4")
		(26 "In12.Cu" signal "GND5")
		(28 "In13.Cu" signal "IN5")
		(30 "In14.Cu" signal "GND6")
		(32 "In15.Cu" signal "IN6")
		(34 "In16.Cu" signal "GND7")
		(2 "B.Cu" signal "BOTTOM")
		(9 "F.Adhes" user "F.Adhesive")
		(11 "B.Adhes" user "B.Adhesive")
		(13 "F.Paste" user "Package Geometry/Pastemask Top")
		(15 "B.Paste" user "Package Geometry/Pastemask Bottom")
		(5 "F.SilkS" user "Ref Des/Silkscreen Top")
		(7 "B.SilkS" user "Ref Des/Silkscreen Bottom")
		(1 "F.Mask" user "Board Geometry/Soldermask Top")
		(3 "B.Mask" user "Board Geometry/Soldermask Bottom")
		(17 "Dwgs.User" user "User.Drawings")
		(19 "Cmts.User" user "User.Comments")
		(21 "Eco1.User" user "User.Eco1")
		(23 "Eco2.User" user "User.Eco2")
		(25 "Edge.Cuts" user "Board Geometry/Outline")
		(27 "Margin" user)
		(31 "F.CrtYd" user "Package Geometry/Place Bound Top")
		(29 "B.CrtYd" user "Package Geometry/Place Bound Bottom")
		(35 "F.Fab" user "Ref Des/Assembly Top")
		(33 "B.Fab" user "Ref Des/Assembly Bottom")
	)
	(footprint ""
		(layer "F.Cu")
		(at 253.506224 -131.067556 180)
		(property "Reference" "R603"
			(at 0 0 180)
			(layer "F.SilkS")
			(hide yes)
			(effects
				(font
					(size 1.27 1.27)
				)
			)
		)
		(property "Value" ""
			(at 0 0 180)
			(layer "F.Fab")
			(effects
				(font
					(size 1.27 1.27)
				)
			)
		)
		(duplicate_pad_numbers_are_jumpers no)
		(fp_line
			(start 0.7874 0.4064)
			(end -0.7874 0.4064)
			(stroke
				(width 0.1524)
				(type default)
			)
			(layer "F.SilkS")
		)
		(fp_line
			(start 0.7874 -0.4064)
			(end 0.7874 0.4064)
			(stroke
				(width 0.1524)
				(type default)
			)
			(layer "F.SilkS")
		)
		(fp_line
			(start -0.7874 0.4064)
			(end -0.7874 -0.4064)
			(stroke
				(width 0.1524)
				(type default)
			)
			(layer "F.SilkS")
		)
		(fp_line
			(start -0.7874 -0.4064)
			(end 0.7874 -0.4064)
			(stroke
				(width 0.1524)
				(type default)
			)
			(layer "F.SilkS")
		)
		(fp_line
			(start 0.67945 0.3048)
			(end 0.120396 0.3048)
			(stroke
				(width 0.1)
				(type default)
			)
			(layer "F.Fab")
		)
		(fp_line
			(start 0.67945 -0.3048)
			(end 0.67945 0.3048)
			(stroke
				(width 0.1)
				(type default)
			)
			(layer "F.Fab")
		)
		(fp_line
			(start 0.12065 -0.2794)
			(end 0.12065 -0.3048)
			(stroke
				(width 0.1)
				(type default)
			)
			(layer "F.Fab")
		)
		(fp_line
			(start 0.12065 -0.3048)
			(end 0.67945 -0.3048)
			(stroke
				(width 0.1)
				(type default)
			)
			(layer "F.Fab")
		)
		(fp_line
			(start 0.120396 0.3048)
			(end 0.120396 0.2794)
			(stroke
				(width 0.1)
				(type default)
			)
			(layer "F.Fab")
		)
		(fp_line
			(start 0.120396 0.2794)
			(end -0.12065 0.2794)
			(stroke
				(width 0.1)
				(type default)
			)
			(layer "F.Fab")
		)
		(fp_line
			(start -0.12065 0.3048)
			(end -0.67945 0.3048)
			(stroke
				(width 0.1)
				(type default)
			)
			(layer "F.Fab")
		)
		(fp_line
			(start -0.12065 0.2794)
			(end -0.12065 0.3048)
			(stroke
				(width 0.1)
				(type default)
			)
			(layer "F.Fab")
		)
		(fp_line
			(start -0.12065 -0.2794)
			(end 0.12065 -0.2794)
			(stroke
				(width 0.1)
				(type default)
			)
			(layer "F.Fab")
		)
		(fp_line
			(start -0.12065 -0.305054)
			(end -0.12065 -0.2794)
			(stroke
				(width 0.1)
				(type default)
			)
			(layer "F.Fab")
		)
		(fp_line
			(start -0.67945 0.3048)
			(end -0.67945 -0.305054)
			(stroke
				(width 0.1)
				(type default)
			)
			(layer "F.Fab")
		)
		(fp_line
			(start -0.67945 -0.305054)
			(end -0.12065 -0.305054)
			(stroke
				(width 0.1)
				(type default)
			)
			(layer "F.Fab")
		)
		(pad "1" smd circle
			(at -0.40005 0 180)
			(size 0 0)
			(layers "F.Cu" "F.Mask" "F.Paste")
			(net "SPI_CPU0_LVC3_CS0_N")
		)
		(pad "2" smd circle
			(at 0.40005 0 180)
			(size 0 0)
			(layers "F.Cu" "F.Mask" "F.Paste")
			(net "SPI_CPU0_LVC3_SCM_CS0_N")
		)
	)
	(footprint ""
		(layer "F.Cu")
		(at 171.26966 -387.763004 180)
		(property "Reference" "R857"
			(at 0 0 180)
			(layer "F.SilkS")
			(hide yes)
			(effects
				(font
					(size 1.27 1.27)
				)
			)
		)
		(property "Value" ""
			(at 0 0 180)
			(layer "F.Fab")
			(effects
				(font
					(size 1.27 1.27)
				)
			)
		)
		(duplicate_pad_numbers_are_jumpers no)
		(fp_line
			(start 0.7874 0.4064)
			(end -0.7874 0.4064)
			(stroke
				(width 0.1524)
				(type default)
			)
			(layer "F.SilkS")
		)
		(fp_line
			(start 0.7874 -0.4064)
			(end 0.7874 0.4064)
			(stroke
				(width 0.1524)
				(type default)
			)
			(layer "F.SilkS")
		)
		(fp_line
			(start -0.7874 0.4064)
			(end -0.7874 -0.4064)
			(stroke
				(width 0.1524)
				(type default)
			)
			(layer "F.SilkS")
		)
		(fp_line
			(start -0.7874 -0.4064)
			(end 0.7874 -0.4064)
			(stroke
				(width 0.1524)
				(type default)
			)
			(layer "F.SilkS")
		)
		(fp_line
			(start 0.67945 0.3048)
			(end 0.120396 0.3048)
			(stroke
				(width 0.1)
				(type default)
			)
			(layer "F.Fab")
		)
		(fp_line
			(start 0.67945 -0.3048)
			(end 0.67945 0.3048)
			(stroke
				(width 0.1)
				(type default)
			)
			(layer "F.Fab")
		)
		(fp_line
			(start 0.12065 -0.2794)
			(end 0.12065 -0.3048)
			(stroke
				(width 0.1)
				(type default)
			)
			(layer "F.Fab")
		)
		(fp_line
			(start 0.12065 -0.3048)
			(end 0.67945 -0.3048)
			(stroke
				(width 0.1)
				(type default)
			)
			(layer "F.Fab")
		)
		(fp_line
			(start 0.120396 0.3048)
			(end 0.120396 0.2794)
			(stroke
				(width 0.1)
				(type default)
			)
			(layer "F.Fab")
		)
		(fp_line
			(start 0.120396 0.2794)
			(end -0.12065 0.2794)
			(stroke
				(width 0.1)
				(type default)
			)
			(layer "F.Fab")
		)
		(fp_line
			(start -0.12065 0.3048)
			(end -0.67945 0.3048)
			(stroke
				(width 0.1)
				(type default)
			)
			(layer "F.Fab")
		)
		(fp_line
			(start -0.12065 0.2794)
			(end -0.12065 0.3048)
			(stroke
				(width 0.1)
				(type default)
			)
			(layer "F.Fab")
		)
		(fp_line
			(start -0.12065 -0.2794)
			(end 0.12065 -0.2794)
			(stroke
				(width 0.1)
				(type default)
			)
			(layer "F.Fab")
		)
		(fp_line
			(start -0.12065 -0.305054)
			(end -0.12065 -0.2794)
			(stroke
				(width 0.1)
				(type default)
			)
			(layer "F.Fab")
		)
		(fp_line
			(start -0.67945 0.3048)
			(end -0.67945 -0.305054)
			(stroke
				(width 0.1)
				(type default)
			)
			(layer "F.Fab")
		)
		(fp_line
			(start -0.67945 -0.305054)
			(end -0.12065 -0.305054)
			(stroke
				(width 0.1)
				(type default)
			)
			(layer "F.Fab")
		)
		(pad "1" smd rect
			(at -0.40005 0)
			(size 0.4572 0.508)
			(layers "F.Cu" "F.Mask" "F.Paste")
			(net "P1V8_CPU1_RT_1D")
		)
		(pad "2" smd rect
			(at 0.40005 0)
			(size 0.4572 0.508)
			(layers "F.Cu" "F.Mask" "F.Paste")
			(net "P1V8_CPU1_RT2_1A_1D")
		)
	)
)
